G04 ================== begin FILE IDENTIFICATION RECORD ==================*
G04 Layout Name:  9049_F0T_FAN_BOARD_MP5048_D_v02_20221209_0830.brd*
G04 Film Name:    pmb.art*
G04 File Format:  Gerber RS274X*
G04 File Origin:  Cadence Allegro 17.2-S081*
G04 Origin Date:  Mon Dec 12 15:05:04 2022*
G04 *
G04 Layer:  DRAWING FORMAT/TITLE_BLOCK_A*
G04 Layer:  VIA CLASS/PASTEMASK_BOTTOM*
G04 Layer:  PACKAGE GEOMETRY/PASTEMASK_BOTTOM*
G04 Layer:  DRAWING FORMAT/TITLE_BLOCK*
G04 Layer:  PIN/PASTEMASK_BOTTOM*
G04 Layer:  MANUFACTURING/PHOTOPLOT_OUTLINE*
G04 Layer:  DRAWING FORMAT/TITLE_DATA_PMB*
G04 *
G04 Offset:    (0.00 0.00)*
G04 Mirror:    No*
G04 Mode:      Positive*
G04 Rotation:  0*
G04 FullContactRelief:  No*
G04 UndefLineWidth:     6.00*
G04 ================== end FILE IDENTIFICATION RECORD ====================*
%FSLAX25Y25*MOIN*%
%IR0*IPPOS*OFA0.00000B0.00000*MIA0B0*SFA1.00000B1.00000*%
%AMMACRO22*
4,1,6,.01378,.01772,
.0059,.01772,
.0059,-.00984,
-.01378,-.00984,
-.01378,-.01772,
.01378,-.01772,
.01378,.01772,
0.0*
%
%ADD22MACRO22*%
%ADD34R,.13X.095*%
%ADD35R,.13X.099*%
%ADD19R,.007X.036*%
%ADD10C,.026*%
%ADD15R,.099X.13*%
%ADD13C,.054*%
%ADD41C,.039*%
%AMMACRO24*
4,1,5,-.04724,-.00591,
-.04724,0.0,
-.04134,.00591,
.04724,.00591,
.04724,-.00591,
-.04724,-.00591,
0.0*
%
%ADD24MACRO24*%
%ADD14R,.054X.054*%
%AMMACRO31*
4,1,28,-.00748,.00052,
-.00984,.00052,
-.00984,.00603,
-.009782,.006705,
-.009607,.007359,
-.009321,.007974,
-.008933,.008529,
-.008455,.009009,
-.0079,.009398,
-.007286,.009685,
-.006632,.009861,
-.005957,.00992,
-.00591,.00992,
.00591,.00992,
.006585,.009869,
.007242,.009701,
.007859,.009421,
.008418,.009039,
.008903,.008565,
.009297,.008015,
.009591,.007404,
.009773,.006751,
.00984,.006077,
.00984,.00603,
.00984,.00052,
.00748,.00052,
.00748,-.00991,
-.00748,-.00991,
-.00748,.00052,
0.0*
%
%ADD31MACRO31*%
%AMMACRO33*
4,1,28,.00052,.00748,
.00052,.00984,
.00603,.00984,
.006705,.009782,
.007359,.009607,
.007974,.009321,
.008529,.008933,
.009009,.008455,
.009398,.0079,
.009685,.007286,
.009861,.006632,
.00992,.005957,
.00992,.00591,
.00992,-.00591,
.009869,-.006585,
.009701,-.007242,
.009421,-.007859,
.009039,-.008418,
.008565,-.008903,
.008015,-.009297,
.007404,-.009591,
.006751,-.009773,
.006077,-.00984,
.00603,-.00984,
.00052,-.00984,
.00052,-.00748,
-.00991,-.00748,
-.00991,.00748,
.00052,.00748,
0.0*
%
%ADD33MACRO33*%
%AMMACRO30*
4,1,28,-.00748,-.00051,
-.00984,-.00051,
-.00984,-.00602,
-.009782,-.006695,
-.009607,-.007349,
-.009321,-.007964,
-.008933,-.008519,
-.008455,-.008998,
-.0079,-.009388,
-.007287,-.009675,
-.006632,-.009851,
-.005958,-.00991,
-.00591,-.00991,
.00591,-.00991,
.006585,-.009859,
.007242,-.009691,
.007859,-.009411,
.008418,-.009029,
.008903,-.008555,
.009297,-.008005,
.00959,-.007394,
.009773,-.006742,
.00984,-.006068,
.00984,-.00602,
.00984,-.00051,
.00748,-.00051,
.00748,.00992,
-.00748,.00992,
-.00748,-.00051,
0.0*
%
%ADD30MACRO30*%
%AMMACRO32*
4,1,28,-.00051,.00748,
-.00051,.00984,
-.00602,.00984,
-.006695,.009782,
-.007349,.009607,
-.007964,.009321,
-.008519,.008933,
-.008998,.008455,
-.009388,.0079,
-.009675,.007287,
-.009851,.006632,
-.00991,.005958,
-.00991,.00591,
-.00991,-.00591,
-.009859,-.006585,
-.009691,-.007242,
-.009411,-.007859,
-.009029,-.008418,
-.008555,-.008903,
-.008005,-.009297,
-.007394,-.00959,
-.006742,-.009773,
-.006068,-.00984,
-.00602,-.00984,
-.00051,-.00984,
-.00051,-.00748,
.00992,-.00748,
.00992,.00748,
-.00051,.00748,
0.0*
%
%ADD32MACRO32*%
%AMMACRO18*
4,1,6,.01378,-.01772,
.0059,-.01772,
.0059,.00984,
-.01378,.00984,
-.01378,.01772,
.01378,.01772,
.01378,-.01772,
0.0*
%
%ADD18MACRO18*%
%AMMACRO20*
4,1,6,-.01378,-.01772,
-.0059,-.01772,
-.0059,.00984,
.01378,.00984,
.01378,.01772,
-.01378,.01772,
-.01378,-.01772,
0.0*
%
%ADD20MACRO20*%
%ADD27R,.02X.02*%
%ADD37R,.05X.04*%
%ADD17R,.04X.05*%
%ADD39R,.02X.018*%
%ADD40R,.018X.02*%
%ADD26R,.016X.024*%
%ADD25R,.046X.013*%
%ADD36R,.032X.028*%
%ADD42R,.028X.032*%
%ADD16R,.046X.062*%
%AMMACRO38*
4,1,5,.04724,.00591,
.04724,0.0,
.04134,-.00591,
-.04724,-.00591,
-.04724,.00591,
.04724,.00591,
0.0*
%
%ADD38MACRO38*%
%ADD23R,.099X.012*%
%AMMACRO29*
4,1,28,-.00052,-.00748,
-.00052,-.00984,
-.00603,-.00984,
-.006705,-.009782,
-.007359,-.009607,
-.007974,-.009321,
-.008529,-.008933,
-.009009,-.008455,
-.009398,-.0079,
-.009685,-.007286,
-.009861,-.006632,
-.00992,-.005957,
-.00992,-.00591,
-.00992,.00591,
-.009869,.006585,
-.009701,.007242,
-.009421,.007859,
-.009039,.008418,
-.008565,.008903,
-.008015,.009297,
-.007404,.009591,
-.006751,.009773,
-.006077,.00984,
-.00603,.00984,
-.00052,.00984,
-.00052,.00748,
.00991,.00748,
.00991,-.00748,
-.00052,-.00748,
0.0*
%
%ADD29MACRO29*%
%AMMACRO12*
4,1,28,.00748,-.00052,
.00984,-.00052,
.00984,-.00603,
.009782,-.006705,
.009607,-.007359,
.009321,-.007974,
.008933,-.008529,
.008455,-.009009,
.0079,-.009398,
.007286,-.009685,
.006632,-.009861,
.005957,-.00992,
.00591,-.00992,
-.00591,-.00992,
-.006585,-.009869,
-.007242,-.009701,
-.007859,-.009421,
-.008418,-.009039,
-.008903,-.008565,
-.009297,-.008015,
-.009591,-.007404,
-.009773,-.006751,
-.00984,-.006077,
-.00984,-.00603,
-.00984,-.00052,
-.00748,-.00052,
-.00748,.00991,
.00748,.00991,
.00748,-.00052,
0.0*
%
%ADD12MACRO12*%
%AMMACRO28*
4,1,28,.00051,-.00748,
.00051,-.00984,
.00602,-.00984,
.006695,-.009782,
.007349,-.009607,
.007964,-.009321,
.008519,-.008933,
.008998,-.008455,
.009388,-.0079,
.009675,-.007287,
.009851,-.006632,
.00991,-.005958,
.00991,-.00591,
.00991,.00591,
.009859,.006585,
.009691,.007242,
.009411,.007859,
.009029,.008418,
.008555,.008903,
.008005,.009297,
.007394,.00959,
.006742,.009773,
.006068,.00984,
.00602,.00984,
.00051,.00984,
.00051,.00748,
-.00992,.00748,
-.00992,-.00748,
.00051,-.00748,
0.0*
%
%ADD28MACRO28*%
%AMMACRO11*
4,1,28,.00748,.00051,
.00984,.00051,
.00984,.00602,
.009782,.006695,
.009607,.007349,
.009321,.007964,
.008933,.008519,
.008455,.008998,
.0079,.009388,
.007287,.009675,
.006632,.009851,
.005958,.00991,
.00591,.00991,
-.00591,.00991,
-.006585,.009859,
-.007242,.009691,
-.007859,.009411,
-.008418,.009029,
-.008903,.008555,
-.009297,.008005,
-.00959,.007394,
-.009773,.006742,
-.00984,.006068,
-.00984,.00602,
-.00984,.00051,
-.00748,.00051,
-.00748,-.00992,
.00748,-.00992,
.00748,.00051,
0.0*
%
%ADD11MACRO11*%
%AMMACRO21*
4,1,6,-.01378,.01772,
-.0059,.01772,
-.0059,-.00984,
.01378,-.00984,
.01378,-.01772,
-.01378,-.01772,
-.01378,.01772,
0.0*
%
%ADD21MACRO21*%
%ADD43C,.006*%
G75*
%LPD*%
G75*
G54D10*
X10291Y249166D03*
X7240Y271043D03*
X12000Y641000D03*
X8612Y967317D03*
X8659Y974808D03*
X12047Y1003400D03*
X20650Y248510D03*
X31657Y249042D03*
X27185Y286228D03*
X18185D03*
X20452Y513547D03*
X27580Y528341D03*
X30380Y648320D03*
X32720Y660000D03*
X12389Y653509D03*
X25023Y663850D03*
Y669850D03*
X32728Y679000D03*
X12500D03*
X14925Y669000D03*
Y690000D03*
X20327Y711174D03*
X13375Y730274D03*
X15012Y745563D03*
X17458Y737184D03*
X13500Y862500D03*
X22630Y975714D03*
X31791Y975500D03*
X19500Y1239500D03*
X47487Y174264D03*
X38383Y280119D03*
X47561Y297728D03*
X40000Y334700D03*
X56925Y503000D03*
Y528500D03*
Y508500D03*
Y523500D03*
Y518500D03*
X57000Y538500D03*
X47499Y649000D03*
X52977Y662650D03*
X56475Y654000D03*
X46950Y666500D03*
X45240Y657000D03*
X56475Y672500D03*
X46950D03*
X52977Y681650D03*
X45240Y682000D03*
X57260Y1024020D03*
X48660Y1025650D03*
X68416Y63842D03*
X61000Y84192D03*
X61300Y66900D03*
X69100Y76100D03*
X75173Y78000D03*
X68500Y70000D03*
X71650Y94259D03*
Y111259D03*
X64025Y92575D03*
X65350Y102000D03*
X71500Y130000D03*
X62716Y129542D03*
X66000Y216800D03*
X80500Y273420D03*
X58561Y280728D03*
X74350Y276685D03*
X70000Y298500D03*
X61420Y299310D03*
X68700Y400000D03*
X78500Y406000D03*
X65900Y413000D03*
X69018Y420378D03*
X67000Y430500D03*
X71000Y427000D03*
X60773Y443728D03*
X74979Y437559D03*
X79500Y449925D03*
X65350Y447500D03*
X70500Y443500D03*
X65250Y470378D03*
X74500Y475000D03*
X68000Y463878D03*
X79293Y523513D03*
X75650Y517770D03*
X68345Y533265D03*
X73500Y562200D03*
X63070Y652400D03*
X68000Y664000D03*
X69000Y669745D03*
X68000Y676500D03*
X59475Y688975D03*
X60000Y696984D03*
X69350Y711940D03*
X68100Y721000D03*
X74075Y732000D03*
X65570Y734500D03*
X58612Y740500D03*
X69340Y758500D03*
X66000Y776000D03*
X61576Y762200D03*
X77816Y764764D03*
X78000Y782500D03*
X68481Y800951D03*
X69018Y783764D03*
X62058Y801075D03*
X67993Y827764D03*
X65350Y818654D03*
X71410Y846500D03*
X64500Y943500D03*
X80000Y980649D03*
X59268Y1007793D03*
X74800Y1003457D03*
X62500Y1025500D03*
X71210Y1024290D03*
X68686Y1139993D03*
X64425Y1165500D03*
X64843Y1194000D03*
X74313Y1178559D03*
X64850Y1179000D03*
X99000Y61000D03*
X87500Y83300D03*
X86000Y92000D03*
X94430Y103830D03*
X88900Y119300D03*
X82500Y389500D03*
X84500Y404000D03*
X82500Y398000D03*
X100835Y446500D03*
X91059Y452760D03*
X91593Y439000D03*
X95000Y462740D03*
X85500Y472975D03*
X86500Y481500D03*
X96502Y501930D03*
X95184Y493787D03*
X98040Y506730D03*
X87500Y522800D03*
X96275Y519750D03*
X84723Y532202D03*
X100505Y561919D03*
X97000Y569153D03*
X90680Y561766D03*
X98780Y617000D03*
X99051Y635051D03*
X87500Y634700D03*
X88300Y639800D03*
X83300Y624100D03*
X103037Y624462D03*
X95032Y660000D03*
X86000Y680000D03*
Y688000D03*
X101309Y675500D03*
X93025Y738000D03*
X99500Y787000D03*
X83000Y804000D03*
X94000Y825740D03*
X83000Y810000D03*
X82000Y833575D03*
X104500Y834500D03*
X115918Y75650D03*
X123500Y115500D03*
X123450Y238523D03*
X127482Y286228D03*
X107000Y389500D03*
X107966Y408260D03*
X112441Y418434D03*
X106850Y441596D03*
X125200Y453800D03*
X113500Y476000D03*
X118490Y495330D03*
X126070Y493931D03*
X112070Y499790D03*
X109000Y485000D03*
X111000Y506000D03*
X115788Y573787D03*
X106977Y561919D03*
X121500Y557500D03*
X114000Y591000D03*
X120000Y581500D03*
X108601Y627084D03*
X118079Y639954D03*
X124499Y660000D03*
X126185Y688915D03*
X123401Y669102D03*
X117500Y689900D03*
X126500Y706500D03*
X119000Y734000D03*
X125075Y715000D03*
X125352Y749277D03*
X114857Y741500D03*
X119836Y761664D03*
X107500Y782530D03*
X125654Y772281D03*
X107365Y776004D03*
X118711Y797500D03*
X125500Y820114D03*
X126000Y834500D03*
X117500Y857575D03*
X126500Y1129000D03*
X109500Y1139500D03*
X135500Y70441D03*
X142000Y74575D03*
X142500Y103342D03*
X138650Y94000D03*
X132500Y99000D03*
X135000Y120500D03*
X137449Y113340D03*
X135750Y132750D03*
X133982Y249166D03*
X140870Y249090D03*
X146133Y248610D03*
X144482Y265728D03*
X147500Y278228D03*
X136482Y286228D03*
X150270Y298590D03*
X135245Y407228D03*
X130500Y432500D03*
X139150Y420193D03*
Y429650D03*
X135349Y468652D03*
X135000Y463000D03*
X129000Y468000D03*
X150575Y504500D03*
X144324Y498325D03*
X145193Y504232D03*
X144335Y509166D03*
X138532Y507500D03*
X150575Y534500D03*
X131500Y634500D03*
X150300Y645900D03*
X141900Y645410D03*
X134575Y659000D03*
X128000Y694500D03*
X133575Y692000D03*
X136500Y728500D03*
X128065Y725566D03*
X146000Y729000D03*
X127983Y736234D03*
X133900Y776000D03*
X132350Y793241D03*
X139650Y785905D03*
X139075Y801984D03*
X141327Y822814D03*
X134525Y815114D03*
X134800Y826614D03*
X146505Y978795D03*
X133982Y979087D03*
X147229Y1004299D03*
X144482Y995649D03*
X128700Y999692D03*
X132175Y1117325D03*
X135800Y1138000D03*
X138650Y1149500D03*
X142500Y1161500D03*
X138650Y1165500D03*
X136800Y1194800D03*
X161100Y216500D03*
X155482Y248728D03*
X165014Y268287D03*
X167858Y279310D03*
X157103Y297803D03*
X170358Y298858D03*
X158858Y332228D03*
X153725Y524500D03*
Y514500D03*
X167190Y529510D03*
X171977Y656850D03*
X166547Y663500D03*
X159051Y671661D03*
X167679Y674254D03*
X167642Y682217D03*
X167060Y692500D03*
X171440Y708767D03*
X156962Y692037D03*
X171586Y735683D03*
X171580Y716500D03*
X171500Y743500D03*
X157000Y979000D03*
X164600Y998649D03*
X167858Y1007500D03*
X156858Y1024500D03*
X166207Y1025077D03*
X165500Y1229900D03*
X183600Y276685D03*
X179000Y298500D03*
X189800Y380300D03*
X188516Y518310D03*
X191991Y536336D03*
X191259Y547500D03*
X182500Y641600D03*
X187050Y652000D03*
Y663500D03*
X177500Y679500D03*
X175475Y668500D03*
X181475Y713000D03*
X193475Y706000D03*
X179000Y694000D03*
X190300Y725200D03*
X192582Y733000D03*
X181475Y747000D03*
X183600Y1005700D03*
X178358Y1024062D03*
X186458Y1106662D03*
X192000Y1240500D03*
X182600Y1228850D03*
G54D11*
X7000Y256712D03*
X6500Y983484D03*
X19000Y256748D03*
X15000D03*
X30000D03*
X18500Y983484D03*
X14500D03*
X30500D03*
X38229Y256748D03*
X34229D03*
X42309D03*
X55500Y292712D03*
X38500Y983484D03*
X34500D03*
X42500D03*
X72561Y1019484D03*
X56500D03*
X143500Y256748D03*
X127482Y256712D03*
X139500Y256748D03*
X135500D03*
X142500Y986669D03*
X126500D03*
X138500D03*
X134500D03*
X162420Y256748D03*
X158420D03*
X154000D03*
X166420D03*
X167000Y292712D03*
X161920Y986669D03*
X157920D03*
X153500D03*
X166000D03*
X169500Y1019484D03*
X183000Y292712D03*
X181500Y1019484D03*
G54D20*
X32874Y223012D03*
Y949784D03*
X65768Y304940D03*
X66268Y1031712D03*
X156565Y223012D03*
Y952933D03*
X175065Y304940D03*
Y1031712D03*
G54D21*
X32874Y241516D03*
Y968288D03*
X65768Y323444D03*
X66268Y1050216D03*
X156565Y241516D03*
Y971437D03*
X175065Y323444D03*
Y1050216D03*
G54D12*
X7000Y253745D03*
X6500Y980517D03*
X19000Y253781D03*
X15000D03*
X30000D03*
X18500Y980517D03*
X14500D03*
X30500D03*
X38229Y253781D03*
X34229D03*
X42309D03*
X55500Y289745D03*
X38500Y980517D03*
X34500D03*
X42500D03*
X72561Y1016517D03*
X56500D03*
X143500Y253781D03*
X127482Y253745D03*
X139500Y253781D03*
X135500D03*
X142500Y983702D03*
X126500D03*
X138500D03*
X134500D03*
X162420Y253781D03*
X158420D03*
X154000D03*
X166420D03*
X167000Y289745D03*
X161920Y983702D03*
X157920D03*
X153500D03*
X166000D03*
X169500Y1016517D03*
X183000Y289745D03*
X181500Y1016517D03*
G54D30*
X11000Y253780D03*
X10500Y980516D03*
X41123Y289708D03*
X45123D03*
X49000Y289716D03*
X37061Y289708D03*
X42123Y1016480D03*
X46123D03*
X50000Y1016516D03*
X38061Y1016480D03*
X59500Y289744D03*
X63500D03*
X68061D03*
X60500Y1016516D03*
X76561D03*
X64500D03*
X68561D03*
X131500Y253780D03*
X147500D03*
X130500Y983701D03*
X146500D03*
X147500Y1016516D03*
X171000Y289744D03*
X152420Y289708D03*
X156420D03*
X160500Y289744D03*
X148500Y289708D03*
X165500Y1016516D03*
X151420Y1016480D03*
X155420D03*
X159500Y1016516D03*
X187000Y289744D03*
X175000D03*
X179000D03*
X185500Y1016516D03*
X173500D03*
X177500D03*
G54D40*
X71075Y501500D03*
X67925D03*
X71075Y497000D03*
X67925D03*
X71075Y519500D03*
X67925D03*
X71075Y524000D03*
X67925D03*
X71075Y515000D03*
X67925D03*
X71075Y510500D03*
X67925D03*
X71075Y506000D03*
X67925D03*
X71075Y528500D03*
X67925D03*
X162575Y498500D03*
X159425D03*
X162575Y503000D03*
X159425D03*
X162575Y507500D03*
X159425D03*
X162575Y512000D03*
X159425D03*
X162575Y516500D03*
X159425D03*
X162575Y525500D03*
X159425D03*
X162575Y521000D03*
X159425D03*
X162575Y530000D03*
X159425D03*
G54D31*
X11000Y256747D03*
X10500Y983483D03*
X41123Y292675D03*
X45123D03*
X49000Y292683D03*
X37061Y292675D03*
X42123Y1019447D03*
X46123D03*
X50000Y1019483D03*
X38061Y1019447D03*
X59500Y292711D03*
X63500D03*
X68061D03*
X60500Y1019483D03*
X76561D03*
X64500D03*
X68561D03*
X131500Y256747D03*
X147500D03*
X130500Y986668D03*
X146500D03*
X147500Y1019483D03*
X171000Y292711D03*
X152420Y292675D03*
X156420D03*
X160500Y292711D03*
X148500Y292675D03*
X165500Y1019483D03*
X151420Y1019447D03*
X155420D03*
X159500Y1019483D03*
X187000Y292711D03*
X175000D03*
X179000D03*
X185500Y1019483D03*
X173500D03*
X177500D03*
G54D13*
X34252Y64606D03*
Y56732D03*
Y48858D03*
X26378Y64606D03*
Y56732D03*
X34252Y88228D03*
Y80354D03*
Y72480D03*
X26378Y88228D03*
Y80354D03*
Y72480D03*
X34252Y103976D03*
Y96102D03*
X26378Y103976D03*
Y96102D03*
X34252Y412244D03*
Y435866D03*
Y427992D03*
Y420118D03*
X26378Y435866D03*
Y427992D03*
Y420118D03*
X34252Y451614D03*
Y443740D03*
X26378Y451614D03*
Y443740D03*
X34252Y467362D03*
Y459488D03*
X26378Y467362D03*
Y459488D03*
X34252Y775630D03*
Y799252D03*
Y791378D03*
Y783504D03*
X26378Y799252D03*
Y791378D03*
Y783504D03*
X34252Y822874D03*
Y815000D03*
Y807126D03*
X26378Y822874D03*
Y815000D03*
Y807126D03*
X34252Y830748D03*
X26378D03*
X34252Y1146890D03*
Y1139016D03*
X26378Y1146890D03*
X34252Y1170512D03*
Y1162638D03*
Y1154764D03*
X26378Y1170512D03*
Y1162638D03*
Y1154764D03*
X34252Y1194134D03*
Y1186260D03*
Y1178386D03*
X26378Y1194134D03*
Y1186260D03*
Y1178386D03*
X169291Y48858D03*
Y56732D03*
Y64606D03*
Y72480D03*
Y80354D03*
Y88228D03*
Y96102D03*
Y103976D03*
Y412244D03*
Y420118D03*
Y427992D03*
Y435866D03*
Y443740D03*
Y451614D03*
Y459488D03*
Y467362D03*
Y775630D03*
Y783504D03*
Y791378D03*
Y799252D03*
Y807126D03*
Y815000D03*
Y822874D03*
Y830748D03*
Y1139016D03*
Y1146890D03*
Y1154764D03*
Y1162638D03*
Y1170512D03*
Y1178386D03*
Y1186260D03*
Y1194134D03*
X177165Y48858D03*
Y56732D03*
Y64606D03*
Y72480D03*
Y80354D03*
Y88228D03*
Y96102D03*
Y412244D03*
Y420118D03*
Y427992D03*
Y435866D03*
Y443740D03*
Y451614D03*
Y459488D03*
Y775630D03*
Y783504D03*
Y791378D03*
Y799252D03*
Y807126D03*
Y815000D03*
Y822874D03*
Y1139016D03*
Y1146890D03*
Y1154764D03*
Y1162638D03*
Y1170512D03*
Y1178386D03*
Y1186260D03*
G54D22*
X13584Y241516D03*
Y968288D03*
X46478Y323444D03*
X46978Y1050216D03*
X137275Y241516D03*
Y971437D03*
X155775Y323444D03*
Y1050216D03*
G54D23*
X17127Y236988D03*
Y233839D03*
Y227540D03*
X29331D03*
Y230689D03*
X17127Y963760D03*
Y960611D03*
Y954312D03*
X29331D03*
Y957461D03*
X50021Y315767D03*
Y318916D03*
X50521Y1045688D03*
Y1042539D03*
X62225Y309468D03*
Y312617D03*
Y318916D03*
X62725Y1036240D03*
Y1039389D03*
Y1045688D03*
X140818Y236988D03*
Y233839D03*
Y227540D03*
Y963760D03*
Y957461D03*
Y966909D03*
X153022Y227540D03*
Y230689D03*
X171522Y309468D03*
Y312617D03*
X159318Y315767D03*
X171522Y318916D03*
X159318D03*
X153022Y957461D03*
Y960610D03*
X171522Y1036240D03*
Y1039389D03*
Y1045688D03*
X159318D03*
Y1042539D03*
G54D32*
X23016Y257500D03*
Y984500D03*
G54D14*
X26378Y48858D03*
Y412244D03*
Y775630D03*
Y1139016D03*
X177165Y103976D03*
Y467362D03*
Y830748D03*
Y1194134D03*
G54D41*
X63000Y1237000D03*
X120000Y267500D03*
X187900Y675200D03*
G54D42*
X176000Y1231100D03*
Y1236900D03*
G54D33*
X25983Y257500D03*
Y984500D03*
G54D24*
X29528Y236988D03*
Y963760D03*
X153219Y236988D03*
Y966909D03*
G54D15*
X15458Y162928D03*
X13837Y887582D03*
X42230Y162928D03*
X40609Y887582D03*
X156214Y169628D03*
X160114Y893200D03*
X182986Y169628D03*
X186886Y893200D03*
G54D43*
G01X-320500Y-470483D02*
Y2626000D01*
X2967000D01*
Y-470483D01*
X-320500D01*
G01X329322Y-314459D02*
Y-319459D01*
G01X327865Y-314459D02*
X330779D01*
G01X335689Y-319459D02*
X333155D01*
Y-314459D01*
X335689D01*
G01X334675Y-316876D02*
X333155D01*
G01X338255Y-314459D02*
Y-319459D01*
X340789D01*
G01X344622Y-319626D02*
X344495Y-319542D01*
Y-319376D01*
X344622Y-319292D01*
X344749Y-319376D01*
Y-319542D01*
X344622Y-319626D01*
G01Y-317376D02*
X344495Y-317292D01*
Y-317126D01*
X344622Y-317042D01*
X344749Y-317126D01*
Y-317292D01*
X344622Y-317376D01*
G01X349405Y-321126D02*
X348772Y-320292D01*
X348455Y-319459D01*
Y-316126D01*
X348772Y-315292D01*
X349405Y-314459D01*
G01X354822D02*
X354315Y-314626D01*
X353935Y-315042D01*
X353682Y-315542D01*
X353492Y-316209D01*
X353429Y-316959D01*
X353492Y-317709D01*
X353682Y-318376D01*
X353935Y-318876D01*
X354315Y-319292D01*
X354822Y-319459D01*
X355329Y-319292D01*
X355709Y-318876D01*
X355962Y-318376D01*
X356152Y-317709D01*
X356215Y-316959D01*
X356152Y-316209D01*
X355962Y-315542D01*
X355709Y-315042D01*
X355329Y-314626D01*
X354822Y-314459D01*
G01X358529Y-318459D02*
X358909Y-319042D01*
X359415Y-319376D01*
X359985Y-319459D01*
X360492Y-319376D01*
X360999Y-318959D01*
X361315Y-318459D01*
X361379Y-317959D01*
X361252Y-317376D01*
X360809Y-316959D01*
X360365Y-316792D01*
X359795D01*
G01X360365D02*
X360745Y-316542D01*
X361062Y-316126D01*
X361189Y-315626D01*
X361062Y-315126D01*
X360745Y-314709D01*
X360175Y-314459D01*
X359605Y-314542D01*
X359035Y-314876D01*
G01X365339Y-321126D02*
X365972Y-320292D01*
X366289Y-319459D01*
Y-316126D01*
X365972Y-315292D01*
X365339Y-314459D01*
G01X368729Y-318459D02*
X369109Y-319042D01*
X369615Y-319376D01*
X370185Y-319459D01*
X370692Y-319376D01*
X371199Y-318959D01*
X371515Y-318459D01*
X371579Y-317959D01*
X371452Y-317376D01*
X371009Y-316959D01*
X370565Y-316792D01*
X369995D01*
G01X370565D02*
X370945Y-316542D01*
X371262Y-316126D01*
X371389Y-315626D01*
X371262Y-315126D01*
X370945Y-314709D01*
X370375Y-314459D01*
X369805Y-314542D01*
X369235Y-314876D01*
G01X374019Y-315292D02*
X374399Y-314792D01*
X374842Y-314542D01*
X375349Y-314459D01*
X375982Y-314626D01*
X376425Y-315042D01*
X376552Y-315542D01*
X376489Y-316042D01*
X376235Y-316459D01*
X374969Y-317292D01*
X374399Y-317876D01*
X374019Y-318709D01*
X373892Y-319459D01*
X376552D01*
G01X380195D02*
X380322Y-318376D01*
X380512Y-317459D01*
X380765Y-316626D01*
X381082Y-315709D01*
X381589Y-314459D01*
X379055D01*
G01X384599Y-317792D02*
X386245D01*
G01X389319Y-315292D02*
X389699Y-314792D01*
X390142Y-314542D01*
X390649Y-314459D01*
X391282Y-314626D01*
X391725Y-315042D01*
X391852Y-315542D01*
X391789Y-316042D01*
X391535Y-316459D01*
X390269Y-317292D01*
X389699Y-317876D01*
X389319Y-318709D01*
X389192Y-319459D01*
X391852D01*
G01X394229Y-318459D02*
X394609Y-319042D01*
X395115Y-319376D01*
X395685Y-319459D01*
X396192Y-319376D01*
X396699Y-318959D01*
X397015Y-318459D01*
X397079Y-317959D01*
X396952Y-317376D01*
X396509Y-316959D01*
X396065Y-316792D01*
X395495D01*
G01X396065D02*
X396445Y-316542D01*
X396762Y-316126D01*
X396889Y-315626D01*
X396762Y-315126D01*
X396445Y-314709D01*
X395875Y-314459D01*
X395305Y-314542D01*
X394735Y-314876D01*
G01X401482Y-319459D02*
Y-314459D01*
X399139Y-318042D01*
X402305D01*
G01X404429Y-318709D02*
X404809Y-319126D01*
X405252Y-319376D01*
X405822Y-319459D01*
X406392Y-319292D01*
X406835Y-318959D01*
X407152Y-318376D01*
X407215Y-317709D01*
X407089Y-317042D01*
X406772Y-316626D01*
X406329Y-316292D01*
X405885Y-316209D01*
X405442Y-316292D01*
X404872Y-316626D01*
X405062Y-314459D01*
X406772D01*
G01X414819Y-319459D02*
Y-314459D01*
X417225D01*
G01X416339Y-316876D02*
X414819D01*
G01X419539Y-319459D02*
X421122Y-314459D01*
X422705Y-319459D01*
G01X422135Y-317709D02*
X420109D01*
G01X424892Y-319459D02*
X427552Y-314459D01*
G01X424892D02*
X427552Y-319459D01*
G01X431322Y-319626D02*
X431195Y-319542D01*
Y-319376D01*
X431322Y-319292D01*
X431449Y-319376D01*
Y-319542D01*
X431322Y-319626D01*
G01Y-317376D02*
X431195Y-317292D01*
Y-317126D01*
X431322Y-317042D01*
X431449Y-317126D01*
Y-317292D01*
X431322Y-317376D01*
G01X436105Y-321126D02*
X435472Y-320292D01*
X435155Y-319459D01*
Y-316126D01*
X435472Y-315292D01*
X436105Y-314459D01*
G01X441522D02*
X441015Y-314626D01*
X440635Y-315042D01*
X440382Y-315542D01*
X440192Y-316209D01*
X440129Y-316959D01*
X440192Y-317709D01*
X440382Y-318376D01*
X440635Y-318876D01*
X441015Y-319292D01*
X441522Y-319459D01*
X442029Y-319292D01*
X442409Y-318876D01*
X442662Y-318376D01*
X442852Y-317709D01*
X442915Y-316959D01*
X442852Y-316209D01*
X442662Y-315542D01*
X442409Y-315042D01*
X442029Y-314626D01*
X441522Y-314459D01*
G01X445229Y-318459D02*
X445609Y-319042D01*
X446115Y-319376D01*
X446685Y-319459D01*
X447192Y-319376D01*
X447699Y-318959D01*
X448015Y-318459D01*
X448079Y-317959D01*
X447952Y-317376D01*
X447509Y-316959D01*
X447065Y-316792D01*
X446495D01*
G01X447065D02*
X447445Y-316542D01*
X447762Y-316126D01*
X447889Y-315626D01*
X447762Y-315126D01*
X447445Y-314709D01*
X446875Y-314459D01*
X446305Y-314542D01*
X445735Y-314876D01*
G01X452039Y-321126D02*
X452672Y-320292D01*
X452989Y-319459D01*
Y-316126D01*
X452672Y-315292D01*
X452039Y-314459D01*
G01X455429Y-318459D02*
X455809Y-319042D01*
X456315Y-319376D01*
X456885Y-319459D01*
X457392Y-319376D01*
X457899Y-318959D01*
X458215Y-318459D01*
X458279Y-317959D01*
X458152Y-317376D01*
X457709Y-316959D01*
X457265Y-316792D01*
X456695D01*
G01X457265D02*
X457645Y-316542D01*
X457962Y-316126D01*
X458089Y-315626D01*
X457962Y-315126D01*
X457645Y-314709D01*
X457075Y-314459D01*
X456505Y-314542D01*
X455935Y-314876D01*
G01X460845Y-318876D02*
X461289Y-319292D01*
X461795Y-319459D01*
X462302Y-319292D01*
X462745Y-318792D01*
X463062Y-318042D01*
X463189Y-317292D01*
Y-316376D01*
X463062Y-315626D01*
X462745Y-314959D01*
X462365Y-314626D01*
X461922Y-314459D01*
X461415Y-314626D01*
X461035Y-314959D01*
X460782Y-315459D01*
X460655Y-316126D01*
X460782Y-316709D01*
X461099Y-317292D01*
X461479Y-317626D01*
X461922Y-317709D01*
X462429Y-317542D01*
X462809Y-317126D01*
X463189Y-316376D01*
G01X466895Y-319459D02*
X467022Y-318376D01*
X467212Y-317459D01*
X467465Y-316626D01*
X467782Y-315709D01*
X468289Y-314459D01*
X465755D01*
G01X471299Y-317792D02*
X472945D01*
G01X475829Y-318459D02*
X476209Y-319042D01*
X476715Y-319376D01*
X477285Y-319459D01*
X477792Y-319376D01*
X478299Y-318959D01*
X478615Y-318459D01*
X478679Y-317959D01*
X478552Y-317376D01*
X478109Y-316959D01*
X477665Y-316792D01*
X477095D01*
G01X477665D02*
X478045Y-316542D01*
X478362Y-316126D01*
X478489Y-315626D01*
X478362Y-315126D01*
X478045Y-314709D01*
X477475Y-314459D01*
X476905Y-314542D01*
X476335Y-314876D01*
G01X481119Y-317376D02*
X481562Y-316792D01*
X481942Y-316459D01*
X482449Y-316292D01*
X482892Y-316459D01*
X483209Y-316792D01*
X483462Y-317292D01*
X483525Y-317876D01*
X483462Y-318376D01*
X483209Y-318876D01*
X482829Y-319292D01*
X482385Y-319459D01*
X481879Y-319292D01*
X481435Y-318792D01*
X481182Y-318042D01*
X481119Y-317209D01*
X481245Y-316126D01*
X481435Y-315542D01*
X481752Y-314959D01*
X482195Y-314542D01*
X482639Y-314459D01*
X483082Y-314626D01*
X483399Y-315042D01*
G01X487422Y-319459D02*
Y-314459D01*
X486662Y-315459D01*
G01Y-319459D02*
X488182D01*
G01X493282D02*
Y-314459D01*
X490939Y-318042D01*
X494105D01*
G01X317322Y-249459D02*
Y-324459D01*
X817322D01*
Y-249459D01*
X317322D01*
G01X512322D02*
Y-324459D01*
G01Y-299459D02*
X615322D01*
Y-274459D01*
G01X512322D02*
X615322D01*
G01X622829Y-309459D02*
Y-304459D01*
X624095D01*
X624602Y-304709D01*
X624982Y-305042D01*
X625299Y-305542D01*
X625552Y-306126D01*
X625615Y-306959D01*
X625552Y-307792D01*
X625299Y-308376D01*
X624982Y-308876D01*
X624602Y-309209D01*
X624095Y-309459D01*
X622829D01*
G01X627739D02*
X629322Y-304459D01*
X630905Y-309459D01*
G01X630335Y-307709D02*
X628309D01*
G01X634422Y-304459D02*
Y-309459D01*
G01X632965Y-304459D02*
X635879D01*
G01X640789Y-309459D02*
X638255D01*
Y-304459D01*
X640789D01*
G01X639775Y-306876D02*
X638255D01*
G01X644622Y-309626D02*
X644495Y-309542D01*
Y-309376D01*
X644622Y-309292D01*
X644749Y-309376D01*
Y-309542D01*
X644622Y-309626D01*
G01Y-307376D02*
X644495Y-307292D01*
Y-307126D01*
X644622Y-307042D01*
X644749Y-307126D01*
Y-307292D01*
X644622Y-307376D01*
G01X617322Y-249459D02*
Y-324459D01*
G01X615322Y-249459D02*
Y-324459D01*
G01X622955Y-284459D02*
Y-279459D01*
X624475D01*
X624982Y-279709D01*
X625362Y-280292D01*
X625489Y-280959D01*
X625362Y-281626D01*
X625045Y-282126D01*
X624475Y-282376D01*
X622955D01*
G01X628182Y-284626D02*
X630462Y-279459D01*
G01X632965Y-284459D02*
Y-279459D01*
X635879Y-284459D01*
Y-279459D01*
G01X639522Y-284626D02*
X639395Y-284542D01*
Y-284376D01*
X639522Y-284292D01*
X639649Y-284376D01*
Y-284542D01*
X639522Y-284626D01*
G01Y-282376D02*
X639395Y-282292D01*
Y-282126D01*
X639522Y-282042D01*
X639649Y-282126D01*
Y-282292D01*
X639522Y-282376D01*
G01X617322Y-299459D02*
X817322D01*
G01X622955Y-259459D02*
Y-254459D01*
X624475D01*
X624982Y-254709D01*
X625362Y-255292D01*
X625489Y-255959D01*
X625362Y-256626D01*
X625045Y-257126D01*
X624475Y-257376D01*
X622955D01*
G01X628055Y-259459D02*
Y-254459D01*
X629639D01*
X630145Y-254709D01*
X630462Y-255042D01*
X630589Y-255709D01*
X630462Y-256376D01*
X630082Y-256792D01*
X629639Y-257042D01*
X628055D01*
G01X629639D02*
X630589Y-259459D01*
G01X634422D02*
X633915Y-259376D01*
X633472Y-259042D01*
X633092Y-258542D01*
X632839Y-257959D01*
X632712Y-257292D01*
Y-256626D01*
X632839Y-255959D01*
X633092Y-255376D01*
X633472Y-254876D01*
X633915Y-254542D01*
X634422Y-254459D01*
X634929Y-254542D01*
X635372Y-254876D01*
X635752Y-255376D01*
X636005Y-255959D01*
X636132Y-256626D01*
Y-257292D01*
X636005Y-257959D01*
X635752Y-258542D01*
X635372Y-259042D01*
X634929Y-259376D01*
X634422Y-259459D01*
G01X638255Y-258459D02*
X638572Y-258959D01*
X638952Y-259292D01*
X639395Y-259459D01*
X639902Y-259292D01*
X640282Y-258959D01*
X640662Y-258459D01*
X640789Y-257792D01*
Y-254459D01*
G01X645889Y-259459D02*
X643355D01*
Y-254459D01*
X645889D01*
G01X644875Y-256876D02*
X643355D01*
G01X651115Y-254876D02*
X650735Y-254626D01*
X650292Y-254459D01*
X649785D01*
X649215Y-254709D01*
X648772Y-255126D01*
X648455Y-255626D01*
X648202Y-256459D01*
X648139Y-257209D01*
X648265Y-257959D01*
X648455Y-258459D01*
X648835Y-258959D01*
X649279Y-259292D01*
X649722Y-259459D01*
X650165D01*
X650609Y-259292D01*
X650989Y-259042D01*
X651305Y-258709D01*
G01X654822Y-254459D02*
Y-259459D01*
G01X653365Y-254459D02*
X656279D01*
G01X659922Y-259626D02*
X659795Y-259542D01*
Y-259376D01*
X659922Y-259292D01*
X660049Y-259376D01*
Y-259542D01*
X659922Y-259626D01*
G01Y-257376D02*
X659795Y-257292D01*
Y-257126D01*
X659922Y-257042D01*
X660049Y-257126D01*
Y-257292D01*
X659922Y-257376D01*
G01X617322Y-274459D02*
X817322D01*
G01X734955Y-301959D02*
Y-306959D01*
X737489D01*
G01X740562Y-301959D02*
X742082D01*
G01X741322D02*
Y-306959D01*
G01X740562D02*
X742082D01*
G01X746929Y-304292D02*
X747182Y-304042D01*
X747372Y-303626D01*
X747499Y-303042D01*
X747372Y-302542D01*
X747119Y-302209D01*
X746675Y-301959D01*
X744965D01*
Y-306959D01*
X747055D01*
X747499Y-306626D01*
X747752Y-306126D01*
X747879Y-305542D01*
X747752Y-304959D01*
X747372Y-304459D01*
X746929Y-304292D01*
X744965D01*
G01X751522Y-307126D02*
X751395Y-307042D01*
Y-306876D01*
X751522Y-306792D01*
X751649Y-306876D01*
Y-307042D01*
X751522Y-307126D01*
G01Y-304876D02*
X751395Y-304792D01*
Y-304626D01*
X751522Y-304542D01*
X751649Y-304626D01*
Y-304792D01*
X751522Y-304876D01*
G01X732322Y-299459D02*
Y-324459D01*
G01X779222Y-301959D02*
Y-306959D01*
G01X777765Y-301959D02*
X780679D01*
G01X784322Y-306959D02*
X783942Y-306876D01*
X783562Y-306542D01*
X783309Y-305959D01*
X783182Y-305292D01*
X783309Y-304626D01*
X783562Y-304042D01*
X783942Y-303709D01*
X784322Y-303626D01*
X784702Y-303709D01*
X785082Y-304042D01*
X785335Y-304626D01*
X785399Y-305292D01*
X785335Y-305959D01*
X785082Y-306542D01*
X784702Y-306876D01*
X784322Y-306959D01*
G01X789422D02*
X789042Y-306876D01*
X788662Y-306542D01*
X788409Y-305959D01*
X788282Y-305292D01*
X788409Y-304626D01*
X788662Y-304042D01*
X789042Y-303709D01*
X789422Y-303626D01*
X789802Y-303709D01*
X790182Y-304042D01*
X790435Y-304626D01*
X790499Y-305292D01*
X790435Y-305959D01*
X790182Y-306542D01*
X789802Y-306876D01*
X789422Y-306959D01*
G01X794522D02*
Y-301959D01*
G01X799622Y-307126D02*
X799495Y-307042D01*
Y-306876D01*
X799622Y-306792D01*
X799749Y-306876D01*
Y-307042D01*
X799622Y-307126D01*
G01Y-304876D02*
X799495Y-304792D01*
Y-304626D01*
X799622Y-304542D01*
X799749Y-304626D01*
Y-304792D01*
X799622Y-304876D01*
G01X775322Y-299459D02*
Y-324459D01*
G01Y-274459D02*
Y-299459D01*
G01X777955Y-281959D02*
Y-276959D01*
X779539D01*
X780045Y-277209D01*
X780362Y-277542D01*
X780489Y-278209D01*
X780362Y-278876D01*
X779982Y-279292D01*
X779539Y-279542D01*
X777955D01*
G01X779539D02*
X780489Y-281959D01*
G01X785589D02*
X783055D01*
Y-276959D01*
X785589D01*
G01X784575Y-279376D02*
X783055D01*
G01X787839Y-276959D02*
X789422Y-281959D01*
X791005Y-276959D01*
G01X794522Y-282126D02*
X794395Y-282042D01*
Y-281876D01*
X794522Y-281792D01*
X794649Y-281876D01*
Y-282042D01*
X794522Y-282126D01*
G01Y-279876D02*
X794395Y-279792D01*
Y-279626D01*
X794522Y-279542D01*
X794649Y-279626D01*
Y-279792D01*
X794522Y-279876D01*
G01X798082Y-326159D02*
X798162Y-326084D01*
X798222Y-325959D01*
X798262Y-325784D01*
X798222Y-325634D01*
X798142Y-325534D01*
X798002Y-325459D01*
X797462D01*
Y-326959D01*
X798122D01*
X798262Y-326859D01*
X798342Y-326709D01*
X798382Y-326534D01*
X798342Y-326359D01*
X798222Y-326209D01*
X798082Y-326159D01*
X797462D01*
G01X799482Y-326959D02*
Y-325959D01*
G01Y-326134D02*
X799402Y-326034D01*
X799282Y-325984D01*
X799142Y-325959D01*
X799002Y-326009D01*
X798882Y-326109D01*
X798802Y-326259D01*
X798762Y-326459D01*
X798802Y-326659D01*
X798882Y-326809D01*
X799002Y-326909D01*
X799142Y-326959D01*
X799282Y-326934D01*
X799402Y-326859D01*
X799482Y-326759D01*
G01X800022Y-326784D02*
X800122Y-326884D01*
X800262Y-326959D01*
X800382D01*
X800502Y-326909D01*
X800582Y-326834D01*
X800622Y-326734D01*
X800602Y-326584D01*
X800522Y-326509D01*
X800162Y-326359D01*
X800082Y-326184D01*
X800122Y-326059D01*
X800202Y-325984D01*
X800322Y-325959D01*
X800442Y-325984D01*
X800562Y-326059D01*
G01X801222Y-326284D02*
X801862D01*
X801802Y-326109D01*
X801702Y-326009D01*
X801562Y-325959D01*
X801422Y-325984D01*
X801302Y-326059D01*
X801222Y-326234D01*
X801182Y-326384D01*
Y-326534D01*
X801222Y-326684D01*
X801322Y-326834D01*
X801442Y-326934D01*
X801582Y-326959D01*
X801722Y-326909D01*
X801862Y-326759D01*
G01X802362Y-326959D02*
Y-325459D01*
G01Y-326209D02*
X802462Y-326059D01*
X802582Y-325984D01*
X802702Y-325959D01*
X802882Y-326009D01*
X803002Y-326109D01*
X803082Y-326284D01*
Y-326484D01*
X803042Y-326684D01*
X802962Y-326834D01*
X802822Y-326934D01*
X802702Y-326959D01*
X802582Y-326934D01*
X802462Y-326859D01*
X802362Y-326734D01*
G01X803922Y-326959D02*
X803802Y-326934D01*
X803682Y-326834D01*
X803602Y-326659D01*
X803562Y-326459D01*
X803602Y-326259D01*
X803682Y-326084D01*
X803802Y-325984D01*
X803922Y-325959D01*
X804042Y-325984D01*
X804162Y-326084D01*
X804242Y-326259D01*
X804262Y-326459D01*
X804242Y-326659D01*
X804162Y-326834D01*
X804042Y-326934D01*
X803922Y-326959D01*
G01X805482D02*
Y-325959D01*
G01Y-326134D02*
X805402Y-326034D01*
X805282Y-325984D01*
X805142Y-325959D01*
X805002Y-326009D01*
X804882Y-326109D01*
X804802Y-326259D01*
X804762Y-326459D01*
X804802Y-326659D01*
X804882Y-326809D01*
X805002Y-326909D01*
X805142Y-326959D01*
X805282Y-326934D01*
X805402Y-326859D01*
X805482Y-326759D01*
G01X806042Y-326959D02*
Y-325959D01*
G01Y-326159D02*
X806142Y-326059D01*
X806242Y-325984D01*
X806382Y-325959D01*
X806482Y-325984D01*
X806602Y-326059D01*
G01X807882Y-325459D02*
Y-326959D01*
G01Y-326734D02*
X807802Y-326859D01*
X807682Y-326934D01*
X807542Y-326959D01*
X807382Y-326909D01*
X807262Y-326784D01*
X807182Y-326634D01*
X807162Y-326459D01*
X807182Y-326284D01*
X807262Y-326134D01*
X807382Y-326009D01*
X807542Y-325959D01*
X807682Y-325984D01*
X807782Y-326034D01*
X807882Y-326134D01*
G01X809522Y-326959D02*
Y-325459D01*
X810022D01*
X810182Y-325534D01*
X810282Y-325634D01*
X810322Y-325834D01*
X810282Y-326034D01*
X810162Y-326159D01*
X810022Y-326234D01*
X809522D01*
G01X810022D02*
X810322Y-326959D01*
G01X810822Y-326284D02*
X811462D01*
X811402Y-326109D01*
X811302Y-326009D01*
X811162Y-325959D01*
X811022Y-325984D01*
X810902Y-326059D01*
X810822Y-326234D01*
X810782Y-326384D01*
Y-326534D01*
X810822Y-326684D01*
X810922Y-326834D01*
X811042Y-326934D01*
X811182Y-326959D01*
X811322Y-326909D01*
X811462Y-326759D01*
G01X811962Y-325959D02*
X812322Y-326959D01*
X812682Y-325959D01*
G01X813522Y-327009D02*
X813482Y-326984D01*
Y-326934D01*
X813522Y-326909D01*
X813562Y-326934D01*
Y-326984D01*
X813522Y-327009D01*
G01X814682Y-326959D02*
X814722Y-326634D01*
X814782Y-326359D01*
X814862Y-326109D01*
X814962Y-325834D01*
X815122Y-325459D01*
X814322D01*
G01X816082Y-326159D02*
X816162Y-326084D01*
X816222Y-325959D01*
X816262Y-325784D01*
X816222Y-325634D01*
X816142Y-325534D01*
X816002Y-325459D01*
X815462D01*
Y-326959D01*
X816122D01*
X816262Y-326859D01*
X816342Y-326709D01*
X816382Y-326534D01*
X816342Y-326359D01*
X816222Y-326209D01*
X816082Y-326159D01*
X815462D01*
G01X-320500Y-470483D02*
Y2626000D01*
X2967000D01*
Y-470483D01*
X-320500D01*
G01X331395Y-304184D02*
X330925Y-303869D01*
X330377Y-303659D01*
X329750D01*
X329045Y-303974D01*
X328497Y-304499D01*
X328105Y-305129D01*
X327792Y-306179D01*
X327714Y-307124D01*
X327870Y-308069D01*
X328105Y-308699D01*
X328575Y-309329D01*
X329124Y-309749D01*
X329672Y-309959D01*
X330220D01*
X330769Y-309749D01*
X331239Y-309434D01*
X331630Y-309014D01*
G01X335032Y-303659D02*
X336912D01*
G01X335972D02*
Y-309959D01*
G01X335032D02*
X336912D01*
G01X342272Y-303659D02*
Y-309959D01*
G01X340470Y-303659D02*
X344074D01*
G01X348572Y-309959D02*
Y-307124D01*
X347005Y-303659D01*
G01X350139D02*
X348572Y-307124D01*
G01X359449Y-308699D02*
X359919Y-309434D01*
X360545Y-309854D01*
X361250Y-309959D01*
X361877Y-309854D01*
X362504Y-309329D01*
X362895Y-308699D01*
X362974Y-308069D01*
X362817Y-307334D01*
X362269Y-306809D01*
X361720Y-306599D01*
X361015D01*
G01X361720D02*
X362190Y-306284D01*
X362582Y-305759D01*
X362739Y-305129D01*
X362582Y-304499D01*
X362190Y-303974D01*
X361485Y-303659D01*
X360780Y-303764D01*
X360075Y-304184D01*
G01X365749Y-308699D02*
X366219Y-309434D01*
X366845Y-309854D01*
X367550Y-309959D01*
X368177Y-309854D01*
X368804Y-309329D01*
X369195Y-308699D01*
X369274Y-308069D01*
X369117Y-307334D01*
X368569Y-306809D01*
X368020Y-306599D01*
X367315D01*
G01X368020D02*
X368490Y-306284D01*
X368882Y-305759D01*
X369039Y-305129D01*
X368882Y-304499D01*
X368490Y-303974D01*
X367785Y-303659D01*
X367080Y-303764D01*
X366375Y-304184D01*
G01X372049Y-308699D02*
X372519Y-309434D01*
X373145Y-309854D01*
X373850Y-309959D01*
X374477Y-309854D01*
X375104Y-309329D01*
X375495Y-308699D01*
X375574Y-308069D01*
X375417Y-307334D01*
X374869Y-306809D01*
X374320Y-306599D01*
X373615D01*
G01X374320D02*
X374790Y-306284D01*
X375182Y-305759D01*
X375339Y-305129D01*
X375182Y-304499D01*
X374790Y-303974D01*
X374085Y-303659D01*
X373380Y-303764D01*
X372675Y-304184D01*
G01X379915Y-309959D02*
X380072Y-308594D01*
X380307Y-307439D01*
X380620Y-306389D01*
X381012Y-305234D01*
X381639Y-303659D01*
X378505D01*
G01X386215Y-309959D02*
X386372Y-308594D01*
X386607Y-307439D01*
X386920Y-306389D01*
X387312Y-305234D01*
X387939Y-303659D01*
X384805D01*
G01X392515Y-311114D02*
X392829Y-309749D01*
G01X398972Y-303659D02*
Y-309959D01*
G01X397170Y-303659D02*
X400774D01*
G01X403314Y-309959D02*
X405272Y-303659D01*
X407230Y-309959D01*
G01X406525Y-307754D02*
X404019D01*
G01X410632Y-303659D02*
X412512D01*
G01X411572D02*
Y-309959D01*
G01X410632D02*
X412512D01*
G01X415522Y-303659D02*
X416619Y-309959D01*
X417872Y-303659D01*
X419125Y-309959D01*
X420222Y-303659D01*
G01X422214Y-309959D02*
X424172Y-303659D01*
X426130Y-309959D01*
G01X425425Y-307754D02*
X422919D01*
G01X428670Y-309959D02*
Y-303659D01*
X432274Y-309959D01*
Y-303659D01*
G01X442680Y-312059D02*
X441897Y-311009D01*
X441505Y-309959D01*
Y-305759D01*
X441897Y-304709D01*
X442680Y-303659D01*
G01X454105Y-309959D02*
Y-303659D01*
X456064D01*
X456690Y-303974D01*
X457082Y-304394D01*
X457239Y-305234D01*
X457082Y-306074D01*
X456612Y-306599D01*
X456064Y-306914D01*
X454105D01*
G01X456064D02*
X457239Y-309959D01*
G01X461972Y-310169D02*
X461815Y-310064D01*
Y-309854D01*
X461972Y-309749D01*
X462129Y-309854D01*
Y-310064D01*
X461972Y-310169D01*
G01X468272Y-309959D02*
X467645Y-309854D01*
X467097Y-309434D01*
X466627Y-308804D01*
X466314Y-308069D01*
X466157Y-307229D01*
Y-306389D01*
X466314Y-305549D01*
X466627Y-304814D01*
X467097Y-304184D01*
X467645Y-303764D01*
X468272Y-303659D01*
X468899Y-303764D01*
X469447Y-304184D01*
X469917Y-304814D01*
X470230Y-305549D01*
X470387Y-306389D01*
Y-307229D01*
X470230Y-308069D01*
X469917Y-308804D01*
X469447Y-309434D01*
X468899Y-309854D01*
X468272Y-309959D01*
G01X474572Y-310169D02*
X474415Y-310064D01*
Y-309854D01*
X474572Y-309749D01*
X474729Y-309854D01*
Y-310064D01*
X474572Y-310169D01*
G01X482595Y-304184D02*
X482125Y-303869D01*
X481577Y-303659D01*
X480950D01*
X480245Y-303974D01*
X479697Y-304499D01*
X479305Y-305129D01*
X478992Y-306179D01*
X478914Y-307124D01*
X479070Y-308069D01*
X479305Y-308699D01*
X479775Y-309329D01*
X480324Y-309749D01*
X480872Y-309959D01*
X481420D01*
X481969Y-309749D01*
X482439Y-309434D01*
X482830Y-309014D01*
G01X487172Y-310169D02*
X487015Y-310064D01*
Y-309854D01*
X487172Y-309749D01*
X487329Y-309854D01*
Y-310064D01*
X487172Y-310169D01*
G01X493864Y-312059D02*
X494647Y-311009D01*
X495039Y-309959D01*
Y-305759D01*
X494647Y-304709D01*
X493864Y-303659D01*
G01X330142Y-296809D02*
X331709D01*
Y-298699D01*
X331239Y-299329D01*
X330690Y-299749D01*
X329907Y-299959D01*
X329124Y-299749D01*
X328575Y-299329D01*
X328105Y-298699D01*
X327792Y-297964D01*
X327635Y-297124D01*
Y-296389D01*
X327792Y-295759D01*
X328105Y-295024D01*
X328575Y-294394D01*
X329045Y-293974D01*
X329672Y-293659D01*
X330220D01*
X330847Y-293869D01*
X331317Y-294289D01*
G01X334249Y-293659D02*
Y-298174D01*
X334562Y-299119D01*
X335189Y-299749D01*
X335972Y-299959D01*
X336755Y-299749D01*
X337382Y-299119D01*
X337695Y-298174D01*
Y-293659D01*
G01X341332D02*
X343212D01*
G01X342272D02*
Y-299959D01*
G01X341332D02*
X343212D01*
G01X346927Y-299119D02*
X347554Y-299644D01*
X348259Y-299959D01*
X348885D01*
X349512Y-299644D01*
X349982Y-299119D01*
X350217Y-298384D01*
X350060Y-297649D01*
X349669Y-297019D01*
X348964Y-296599D01*
X348024Y-296389D01*
X347475Y-295969D01*
X347240Y-295234D01*
X347397Y-294499D01*
X347789Y-293974D01*
X348337Y-293659D01*
X348885D01*
X349434Y-293869D01*
X349904Y-294394D01*
G01X353227Y-299959D02*
Y-293659D01*
G01X356517D02*
Y-299959D01*
G01Y-296809D02*
X353227D01*
G01X359214Y-299959D02*
X361172Y-293659D01*
X363130Y-299959D01*
G01X362425Y-297754D02*
X359919D01*
G01X365670Y-299959D02*
Y-293659D01*
X369274Y-299959D01*
Y-293659D01*
G01X378349Y-299959D02*
Y-293659D01*
X379915D01*
X380542Y-293974D01*
X381012Y-294394D01*
X381404Y-295024D01*
X381717Y-295759D01*
X381795Y-296809D01*
X381717Y-297859D01*
X381404Y-298594D01*
X381012Y-299224D01*
X380542Y-299644D01*
X379915Y-299959D01*
X378349D01*
G01X385432Y-293659D02*
X387312D01*
G01X386372D02*
Y-299959D01*
G01X385432D02*
X387312D01*
G01X391027Y-299119D02*
X391654Y-299644D01*
X392359Y-299959D01*
X392985D01*
X393612Y-299644D01*
X394082Y-299119D01*
X394317Y-298384D01*
X394160Y-297649D01*
X393769Y-297019D01*
X393064Y-296599D01*
X392124Y-296389D01*
X391575Y-295969D01*
X391340Y-295234D01*
X391497Y-294499D01*
X391889Y-293974D01*
X392437Y-293659D01*
X392985D01*
X393534Y-293869D01*
X394004Y-294394D01*
G01X398972Y-293659D02*
Y-299959D01*
G01X397170Y-293659D02*
X400774D01*
G01X405272Y-300169D02*
X405115Y-300064D01*
Y-299854D01*
X405272Y-299749D01*
X405429Y-299854D01*
Y-300064D01*
X405272Y-300169D01*
G01X411415Y-301114D02*
X411729Y-299749D01*
G01X417872Y-293659D02*
Y-299959D01*
G01X416070Y-293659D02*
X419674D01*
G01X422214Y-299959D02*
X424172Y-293659D01*
X426130Y-299959D01*
G01X425425Y-297754D02*
X422919D01*
G01X430472Y-299959D02*
X429845Y-299854D01*
X429297Y-299434D01*
X428827Y-298804D01*
X428514Y-298069D01*
X428357Y-297229D01*
Y-296389D01*
X428514Y-295549D01*
X428827Y-294814D01*
X429297Y-294184D01*
X429845Y-293764D01*
X430472Y-293659D01*
X431099Y-293764D01*
X431647Y-294184D01*
X432117Y-294814D01*
X432430Y-295549D01*
X432587Y-296389D01*
Y-297229D01*
X432430Y-298069D01*
X432117Y-298804D01*
X431647Y-299434D01*
X431099Y-299854D01*
X430472Y-299959D01*
G01X436772D02*
Y-297124D01*
X435205Y-293659D01*
G01X438339D02*
X436772Y-297124D01*
G01X441349Y-293659D02*
Y-298174D01*
X441662Y-299119D01*
X442289Y-299749D01*
X443072Y-299959D01*
X443855Y-299749D01*
X444482Y-299119D01*
X444795Y-298174D01*
Y-293659D01*
G01X447414Y-299959D02*
X449372Y-293659D01*
X451330Y-299959D01*
G01X450625Y-297754D02*
X448119D01*
G01X453870Y-299959D02*
Y-293659D01*
X457474Y-299959D01*
Y-293659D01*
G01X327870Y-289959D02*
Y-283659D01*
X331474Y-289959D01*
Y-283659D01*
G01X335972Y-289959D02*
X335345Y-289854D01*
X334797Y-289434D01*
X334327Y-288804D01*
X334014Y-288069D01*
X333857Y-287229D01*
Y-286389D01*
X334014Y-285549D01*
X334327Y-284814D01*
X334797Y-284184D01*
X335345Y-283764D01*
X335972Y-283659D01*
X336599Y-283764D01*
X337147Y-284184D01*
X337617Y-284814D01*
X337930Y-285549D01*
X338087Y-286389D01*
Y-287229D01*
X337930Y-288069D01*
X337617Y-288804D01*
X337147Y-289434D01*
X336599Y-289854D01*
X335972Y-289959D01*
G01X342272Y-290169D02*
X342115Y-290064D01*
Y-289854D01*
X342272Y-289749D01*
X342429Y-289854D01*
Y-290064D01*
X342272Y-290169D01*
G01X347084Y-284709D02*
X347554Y-284079D01*
X348102Y-283764D01*
X348729Y-283659D01*
X349512Y-283869D01*
X350060Y-284394D01*
X350217Y-285024D01*
X350139Y-285654D01*
X349825Y-286179D01*
X348259Y-287229D01*
X347554Y-287964D01*
X347084Y-289014D01*
X346927Y-289959D01*
X350217D01*
G01X354872D02*
Y-283659D01*
X353932Y-284919D01*
G01Y-289959D02*
X355812D01*
G01X361172D02*
Y-283659D01*
X360232Y-284919D01*
G01Y-289959D02*
X362112D01*
G01X367315Y-291114D02*
X367629Y-289749D01*
G01X371422Y-283659D02*
X372519Y-289959D01*
X373772Y-283659D01*
X375025Y-289959D01*
X376122Y-283659D01*
G01X381639Y-289959D02*
X378505D01*
Y-283659D01*
X381639D01*
G01X380385Y-286704D02*
X378505D01*
G01X384570Y-289959D02*
Y-283659D01*
X388174Y-289959D01*
Y-283659D01*
G01X391027Y-289959D02*
Y-283659D01*
G01X394317D02*
Y-289959D01*
G01Y-286809D02*
X391027D01*
G01X397249Y-283659D02*
Y-288174D01*
X397562Y-289119D01*
X398189Y-289749D01*
X398972Y-289959D01*
X399755Y-289749D01*
X400382Y-289119D01*
X400695Y-288174D01*
Y-283659D01*
G01X403314Y-289959D02*
X405272Y-283659D01*
X407230Y-289959D01*
G01X406525Y-287754D02*
X404019D01*
G01X416384Y-284709D02*
X416854Y-284079D01*
X417402Y-283764D01*
X418029Y-283659D01*
X418812Y-283869D01*
X419360Y-284394D01*
X419517Y-285024D01*
X419439Y-285654D01*
X419125Y-286179D01*
X417559Y-287229D01*
X416854Y-287964D01*
X416384Y-289014D01*
X416227Y-289959D01*
X419517D01*
G01X422370D02*
Y-283659D01*
X425974Y-289959D01*
Y-283659D01*
G01X428749Y-289959D02*
Y-283659D01*
X430315D01*
X430942Y-283974D01*
X431412Y-284394D01*
X431804Y-285024D01*
X432117Y-285759D01*
X432195Y-286809D01*
X432117Y-287859D01*
X431804Y-288594D01*
X431412Y-289224D01*
X430942Y-289644D01*
X430315Y-289959D01*
X428749D01*
G01X441505D02*
Y-283659D01*
X443464D01*
X444090Y-283974D01*
X444482Y-284394D01*
X444639Y-285234D01*
X444482Y-286074D01*
X444012Y-286599D01*
X443464Y-286914D01*
X441505D01*
G01X443464D02*
X444639Y-289959D01*
G01X447649D02*
Y-283659D01*
X449215D01*
X449842Y-283974D01*
X450312Y-284394D01*
X450704Y-285024D01*
X451017Y-285759D01*
X451095Y-286809D01*
X451017Y-287859D01*
X450704Y-288594D01*
X450312Y-289224D01*
X449842Y-289644D01*
X449215Y-289959D01*
X447649D01*
G01X455672Y-290169D02*
X455515Y-290064D01*
Y-289854D01*
X455672Y-289749D01*
X455829Y-289854D01*
Y-290064D01*
X455672Y-290169D01*
G01X351972Y-279259D02*
X349452Y-278842D01*
X347247Y-277176D01*
X345357Y-274676D01*
X344097Y-271759D01*
X343467Y-268426D01*
Y-265092D01*
X344097Y-261759D01*
X345357Y-258842D01*
X347247Y-256343D01*
X349452Y-254676D01*
X351972Y-254259D01*
X354492Y-254676D01*
X356697Y-256343D01*
X358587Y-258842D01*
X359847Y-261759D01*
X360477Y-265092D01*
Y-268426D01*
X359847Y-271759D01*
X358587Y-274676D01*
X356697Y-277176D01*
X354492Y-278842D01*
X351972Y-279259D01*
G01X354492Y-272592D02*
X358272Y-279259D01*
G01X371817Y-262593D02*
Y-274259D01*
X373077Y-277176D01*
X374967Y-278842D01*
X377172Y-279259D01*
X379377Y-278842D01*
X381267Y-277176D01*
X382527Y-274259D01*
G01Y-279259D02*
Y-262593D01*
G01X408042Y-279259D02*
Y-262593D01*
G01Y-265509D02*
X406782Y-263843D01*
X404892Y-263009D01*
X402687Y-262593D01*
X400482Y-263426D01*
X398592Y-265092D01*
X397332Y-267593D01*
X396702Y-270926D01*
X397332Y-274259D01*
X398592Y-276760D01*
X400482Y-278426D01*
X402687Y-279259D01*
X404892Y-278842D01*
X406782Y-277593D01*
X408042Y-275926D01*
G01X422217Y-279259D02*
Y-262593D01*
G01Y-266759D02*
X423477Y-264676D01*
X425367Y-263009D01*
X427887Y-262593D01*
X430092Y-263009D01*
X431982Y-264676D01*
X432927Y-267593D01*
Y-279259D01*
G01X452772Y-254259D02*
Y-279259D01*
G01X448362Y-262593D02*
X457182D01*
G01X483642Y-279259D02*
Y-262593D01*
G01Y-265509D02*
X482382Y-263843D01*
X480492Y-263009D01*
X478287Y-262593D01*
X476082Y-263426D01*
X474192Y-265092D01*
X472932Y-267593D01*
X472302Y-270926D01*
X472932Y-274259D01*
X474192Y-276760D01*
X476082Y-278426D01*
X478287Y-279259D01*
X480492Y-278842D01*
X482382Y-277593D01*
X483642Y-275926D01*
G01X534822Y-291959D02*
Y-283959D01*
X537222D01*
X538022Y-284359D01*
X538622Y-285292D01*
X538822Y-286359D01*
X538622Y-287426D01*
X538122Y-288226D01*
X537222Y-288626D01*
X534822D01*
G01X542322Y-291959D02*
X544822Y-283959D01*
X547322Y-291959D01*
G01X546422Y-289159D02*
X543222D01*
G01X550722Y-290893D02*
X551522Y-291559D01*
X552422Y-291959D01*
X553222D01*
X554022Y-291559D01*
X554622Y-290893D01*
X554922Y-289959D01*
X554722Y-289026D01*
X554222Y-288226D01*
X553322Y-287692D01*
X552122Y-287426D01*
X551422Y-286892D01*
X551122Y-285959D01*
X551322Y-285026D01*
X551822Y-284359D01*
X552522Y-283959D01*
X553222D01*
X553922Y-284226D01*
X554522Y-284892D01*
G01X560822Y-283959D02*
Y-291959D01*
G01X558522Y-283959D02*
X563122D01*
G01X567522Y-289292D02*
X570122D01*
G01X577622Y-287692D02*
X578022Y-287292D01*
X578322Y-286626D01*
X578522Y-285692D01*
X578322Y-284892D01*
X577922Y-284359D01*
X577222Y-283959D01*
X574522D01*
Y-291959D01*
X577822D01*
X578522Y-291426D01*
X578922Y-290626D01*
X579122Y-289692D01*
X578922Y-288759D01*
X578322Y-287959D01*
X577622Y-287692D01*
X574522D01*
G01X584822Y-291959D02*
X584022Y-291826D01*
X583322Y-291292D01*
X582722Y-290492D01*
X582322Y-289559D01*
X582122Y-288492D01*
Y-287426D01*
X582322Y-286359D01*
X582722Y-285426D01*
X583322Y-284626D01*
X584022Y-284092D01*
X584822Y-283959D01*
X585622Y-284092D01*
X586322Y-284626D01*
X586922Y-285426D01*
X587322Y-286359D01*
X587522Y-287426D01*
Y-288492D01*
X587322Y-289559D01*
X586922Y-290492D01*
X586322Y-291292D01*
X585622Y-291826D01*
X584822Y-291959D01*
G01X592822Y-283959D02*
Y-291959D01*
G01X590522Y-283959D02*
X595122D01*
G01X523322Y-258959D02*
Y-266959D01*
X527322D01*
G01X535122D02*
Y-261626D01*
G01Y-262559D02*
X534722Y-262026D01*
X534122Y-261759D01*
X533422Y-261626D01*
X532722Y-261892D01*
X532122Y-262426D01*
X531722Y-263226D01*
X531522Y-264292D01*
X531722Y-265359D01*
X532122Y-266159D01*
X532722Y-266692D01*
X533422Y-266959D01*
X534122Y-266826D01*
X534722Y-266426D01*
X535122Y-265893D01*
G01X539222Y-269359D02*
X539822Y-269626D01*
X540622Y-269359D01*
X541122Y-268826D01*
X541522Y-268159D01*
X542122Y-266026D01*
X543422Y-261626D01*
G01X540222D02*
X542122Y-266026D01*
G01X547822Y-263359D02*
X551022D01*
X550722Y-262426D01*
X550222Y-261892D01*
X549522Y-261626D01*
X548822Y-261759D01*
X548222Y-262159D01*
X547822Y-263092D01*
X547622Y-263893D01*
Y-264692D01*
X547822Y-265492D01*
X548322Y-266292D01*
X548922Y-266826D01*
X549622Y-266959D01*
X550322Y-266692D01*
X551022Y-265893D01*
G01X555922Y-266959D02*
Y-261626D01*
G01Y-262692D02*
X556422Y-262159D01*
X556922Y-261759D01*
X557622Y-261626D01*
X558122Y-261759D01*
X558722Y-262159D01*
G01X542022Y-316959D02*
Y-308959D01*
X546622Y-316959D01*
Y-308959D01*
G01X552322Y-311626D02*
Y-316959D01*
G01Y-309492D02*
X552122Y-309359D01*
Y-309092D01*
X552322Y-308959D01*
X552522Y-309092D01*
Y-309359D01*
X552322Y-309492D01*
G01X558622Y-316959D02*
Y-311626D01*
G01Y-312959D02*
X559022Y-312292D01*
X559622Y-311759D01*
X560422Y-311626D01*
X561122Y-311759D01*
X561722Y-312292D01*
X562022Y-313226D01*
Y-316959D01*
G01X570122D02*
Y-311626D01*
G01Y-312559D02*
X569722Y-312026D01*
X569122Y-311759D01*
X568422Y-311626D01*
X567722Y-311892D01*
X567122Y-312426D01*
X566722Y-313226D01*
X566522Y-314292D01*
X566722Y-315359D01*
X567122Y-316159D01*
X567722Y-316692D01*
X568422Y-316959D01*
X569122Y-316826D01*
X569722Y-316426D01*
X570122Y-315893D01*
G01X649922Y-310292D02*
X650522Y-309492D01*
X651222Y-309092D01*
X652022Y-308959D01*
X653022Y-309226D01*
X653722Y-309892D01*
X653922Y-310692D01*
X653822Y-311493D01*
X653422Y-312159D01*
X651422Y-313492D01*
X650522Y-314426D01*
X649922Y-315759D01*
X649722Y-316959D01*
X653922D01*
G01X659822Y-308959D02*
X659022Y-309226D01*
X658422Y-309892D01*
X658022Y-310692D01*
X657722Y-311759D01*
X657622Y-312959D01*
X657722Y-314159D01*
X658022Y-315226D01*
X658422Y-316026D01*
X659022Y-316692D01*
X659822Y-316959D01*
X660622Y-316692D01*
X661222Y-316026D01*
X661622Y-315226D01*
X661922Y-314159D01*
X662022Y-312959D01*
X661922Y-311759D01*
X661622Y-310692D01*
X661222Y-309892D01*
X660622Y-309226D01*
X659822Y-308959D01*
G01X665922Y-310292D02*
X666522Y-309492D01*
X667222Y-309092D01*
X668022Y-308959D01*
X669022Y-309226D01*
X669722Y-309892D01*
X669922Y-310692D01*
X669822Y-311493D01*
X669422Y-312159D01*
X667422Y-313492D01*
X666522Y-314426D01*
X665922Y-315759D01*
X665722Y-316959D01*
X669922D01*
G01X673922Y-310292D02*
X674522Y-309492D01*
X675222Y-309092D01*
X676022Y-308959D01*
X677022Y-309226D01*
X677722Y-309892D01*
X677922Y-310692D01*
X677822Y-311493D01*
X677422Y-312159D01*
X675422Y-313492D01*
X674522Y-314426D01*
X673922Y-315759D01*
X673722Y-316959D01*
X677922D01*
G01X682022Y-317226D02*
X685622Y-308959D01*
G01X691822Y-316959D02*
Y-308959D01*
X690622Y-310559D01*
G01Y-316959D02*
X693022D01*
G01X697922Y-310292D02*
X698522Y-309492D01*
X699222Y-309092D01*
X700022Y-308959D01*
X701022Y-309226D01*
X701722Y-309892D01*
X701922Y-310692D01*
X701822Y-311493D01*
X701422Y-312159D01*
X699422Y-313492D01*
X698522Y-314426D01*
X697922Y-315759D01*
X697722Y-316959D01*
X701922D01*
G01X706022Y-317226D02*
X709622Y-308959D01*
G01X715822D02*
X715022Y-309226D01*
X714422Y-309892D01*
X714022Y-310692D01*
X713722Y-311759D01*
X713622Y-312959D01*
X713722Y-314159D01*
X714022Y-315226D01*
X714422Y-316026D01*
X715022Y-316692D01*
X715822Y-316959D01*
X716622Y-316692D01*
X717222Y-316026D01*
X717622Y-315226D01*
X717922Y-314159D01*
X718022Y-312959D01*
X717922Y-311759D01*
X717622Y-310692D01*
X717222Y-309892D01*
X716622Y-309226D01*
X715822Y-308959D01*
G01X722122Y-316026D02*
X722822Y-316692D01*
X723622Y-316959D01*
X724422Y-316692D01*
X725122Y-315893D01*
X725622Y-314692D01*
X725822Y-313492D01*
Y-312026D01*
X725622Y-310826D01*
X725122Y-309759D01*
X724522Y-309226D01*
X723822Y-308959D01*
X723022Y-309226D01*
X722422Y-309759D01*
X722022Y-310559D01*
X721822Y-311626D01*
X722022Y-312559D01*
X722522Y-313492D01*
X723122Y-314026D01*
X723822Y-314159D01*
X724622Y-313893D01*
X725222Y-313226D01*
X725822Y-312026D01*
G01X649622Y-291959D02*
Y-283959D01*
X651622D01*
X652422Y-284359D01*
X653022Y-284892D01*
X653522Y-285692D01*
X653922Y-286626D01*
X654022Y-287959D01*
X653922Y-289292D01*
X653522Y-290226D01*
X653022Y-291026D01*
X652422Y-291559D01*
X651622Y-291959D01*
X649622D01*
G01X657322D02*
X659822Y-283959D01*
X662322Y-291959D01*
G01X661422Y-289159D02*
X658222D01*
G01X667822Y-283959D02*
X667022Y-284226D01*
X666422Y-284892D01*
X666022Y-285692D01*
X665722Y-286759D01*
X665622Y-287959D01*
X665722Y-289159D01*
X666022Y-290226D01*
X666422Y-291026D01*
X667022Y-291692D01*
X667822Y-291959D01*
X668622Y-291692D01*
X669222Y-291026D01*
X669622Y-290226D01*
X669922Y-289159D01*
X670022Y-287959D01*
X669922Y-286759D01*
X669622Y-285692D01*
X669222Y-284892D01*
X668622Y-284226D01*
X667822Y-283959D01*
G01X673922Y-291959D02*
Y-283959D01*
X677722D01*
G01X676322Y-287826D02*
X673922D01*
G01X683822Y-283959D02*
X683022Y-284226D01*
X682422Y-284892D01*
X682022Y-285692D01*
X681722Y-286759D01*
X681622Y-287959D01*
X681722Y-289159D01*
X682022Y-290226D01*
X682422Y-291026D01*
X683022Y-291692D01*
X683822Y-291959D01*
X684622Y-291692D01*
X685222Y-291026D01*
X685622Y-290226D01*
X685922Y-289159D01*
X686022Y-287959D01*
X685922Y-286759D01*
X685622Y-285692D01*
X685222Y-284892D01*
X684622Y-284226D01*
X683822Y-283959D01*
G01X691822D02*
Y-291959D01*
G01X689522Y-283959D02*
X694122D01*
G01X697922Y-291959D02*
Y-283959D01*
X701722D01*
G01X700322Y-287826D02*
X697922D01*
G01X708622Y-287692D02*
X709022Y-287292D01*
X709322Y-286626D01*
X709522Y-285692D01*
X709322Y-284892D01*
X708922Y-284359D01*
X708222Y-283959D01*
X705522D01*
Y-291959D01*
X708822D01*
X709522Y-291426D01*
X709922Y-290626D01*
X710122Y-289692D01*
X709922Y-288759D01*
X709322Y-287959D01*
X708622Y-287692D01*
X705522D01*
G01X713922Y-288626D02*
X714622Y-287692D01*
X715222Y-287159D01*
X716022Y-286892D01*
X716722Y-287159D01*
X717222Y-287692D01*
X717622Y-288492D01*
X717722Y-289426D01*
X717622Y-290226D01*
X717222Y-291026D01*
X716622Y-291692D01*
X715922Y-291959D01*
X715122Y-291692D01*
X714422Y-290893D01*
X714022Y-289692D01*
X713922Y-288359D01*
X714122Y-286626D01*
X714422Y-285692D01*
X714922Y-284759D01*
X715622Y-284092D01*
X716322Y-283959D01*
X717022Y-284226D01*
X717522Y-284892D01*
G01X721622Y-291959D02*
Y-283959D01*
X723622D01*
X724422Y-284359D01*
X725022Y-284892D01*
X725522Y-285692D01*
X725922Y-286626D01*
X726022Y-287959D01*
X725922Y-289292D01*
X725522Y-290226D01*
X725022Y-291026D01*
X724422Y-291559D01*
X723622Y-291959D01*
X721622D01*
G01X731822Y-283959D02*
X731022Y-284226D01*
X730422Y-284892D01*
X730022Y-285692D01*
X729722Y-286759D01*
X729622Y-287959D01*
X729722Y-289159D01*
X730022Y-290226D01*
X730422Y-291026D01*
X731022Y-291692D01*
X731822Y-291959D01*
X732622Y-291692D01*
X733222Y-291026D01*
X733622Y-290226D01*
X733922Y-289159D01*
X734022Y-287959D01*
X733922Y-286759D01*
X733622Y-285692D01*
X733222Y-284892D01*
X732622Y-284226D01*
X731822Y-283959D01*
G01X649862Y-270000D02*
Y-263700D01*
X652838D01*
G01X651742Y-266745D02*
X649862D01*
G01X657650Y-263700D02*
X657023Y-263910D01*
X656553Y-264435D01*
X656240Y-265065D01*
X656005Y-265905D01*
X655927Y-266850D01*
X656005Y-267795D01*
X656240Y-268635D01*
X656553Y-269265D01*
X657023Y-269790D01*
X657650Y-270000D01*
X658277Y-269790D01*
X658747Y-269265D01*
X659060Y-268635D01*
X659295Y-267795D01*
X659373Y-266850D01*
X659295Y-265905D01*
X659060Y-265065D01*
X658747Y-264435D01*
X658277Y-263910D01*
X657650Y-263700D01*
G01X663950D02*
Y-270000D01*
G01X662148Y-263700D02*
X665752D01*
G01X667900Y-272100D02*
X672600D01*
G01X674983Y-270000D02*
Y-263700D01*
X676863D01*
X677490Y-264015D01*
X677960Y-264750D01*
X678117Y-265590D01*
X677960Y-266430D01*
X677568Y-267060D01*
X676863Y-267375D01*
X674983D01*
G01X684573Y-264225D02*
X684103Y-263910D01*
X683555Y-263700D01*
X682928D01*
X682223Y-264015D01*
X681675Y-264540D01*
X681283Y-265170D01*
X680970Y-266220D01*
X680892Y-267165D01*
X681048Y-268110D01*
X681283Y-268740D01*
X681753Y-269370D01*
X682302Y-269790D01*
X682850Y-270000D01*
X683398D01*
X683947Y-269790D01*
X684417Y-269475D01*
X684808Y-269055D01*
G01X689777Y-266640D02*
X690090Y-266325D01*
X690325Y-265800D01*
X690482Y-265065D01*
X690325Y-264435D01*
X690012Y-264015D01*
X689463Y-263700D01*
X687348D01*
Y-270000D01*
X689933D01*
X690482Y-269580D01*
X690795Y-268950D01*
X690952Y-268215D01*
X690795Y-267480D01*
X690325Y-266850D01*
X689777Y-266640D01*
X687348D01*
G01X693100Y-272100D02*
X697800D01*
G01X700262Y-270000D02*
Y-263700D01*
X703238D01*
G01X702142Y-266745D02*
X700262D01*
G01X706092Y-270000D02*
X708050Y-263700D01*
X710008Y-270000D01*
G01X709303Y-267795D02*
X706797D01*
G01X712548Y-270000D02*
Y-263700D01*
X716152Y-270000D01*
Y-263700D01*
G01X718300Y-272100D02*
X723000D01*
G01X727577Y-266640D02*
X727890Y-266325D01*
X728125Y-265800D01*
X728282Y-265065D01*
X728125Y-264435D01*
X727812Y-264015D01*
X727263Y-263700D01*
X725148D01*
Y-270000D01*
X727733D01*
X728282Y-269580D01*
X728595Y-268950D01*
X728752Y-268215D01*
X728595Y-267480D01*
X728125Y-266850D01*
X727577Y-266640D01*
X725148D01*
G01X733250Y-270000D02*
X732623Y-269895D01*
X732075Y-269475D01*
X731605Y-268845D01*
X731292Y-268110D01*
X731135Y-267270D01*
Y-266430D01*
X731292Y-265590D01*
X731605Y-264855D01*
X732075Y-264225D01*
X732623Y-263805D01*
X733250Y-263700D01*
X733877Y-263805D01*
X734425Y-264225D01*
X734895Y-264855D01*
X735208Y-265590D01*
X735365Y-266430D01*
Y-267270D01*
X735208Y-268110D01*
X734895Y-268845D01*
X734425Y-269475D01*
X733877Y-269895D01*
X733250Y-270000D01*
G01X737592D02*
X739550Y-263700D01*
X741508Y-270000D01*
G01X740803Y-267795D02*
X738297D01*
G01X744283Y-270000D02*
Y-263700D01*
X746242D01*
X746868Y-264015D01*
X747260Y-264435D01*
X747417Y-265275D01*
X747260Y-266115D01*
X746790Y-266640D01*
X746242Y-266955D01*
X744283D01*
G01X746242D02*
X747417Y-270000D01*
G01X750427D02*
Y-263700D01*
X751993D01*
X752620Y-264015D01*
X753090Y-264435D01*
X753482Y-265065D01*
X753795Y-265800D01*
X753873Y-266850D01*
X753795Y-267900D01*
X753482Y-268635D01*
X753090Y-269265D01*
X752620Y-269685D01*
X751993Y-270000D01*
X750427D01*
G01X756100Y-272100D02*
X760800D01*
G01X762713Y-270000D02*
Y-263700D01*
X764750Y-268950D01*
X766787Y-263700D01*
Y-270000D01*
G01X769483D02*
Y-263700D01*
X771363D01*
X771990Y-264015D01*
X772460Y-264750D01*
X772617Y-265590D01*
X772460Y-266430D01*
X772068Y-267060D01*
X771363Y-267375D01*
X769483D01*
G01X775627Y-269055D02*
X776097Y-269580D01*
X776645Y-269895D01*
X777350Y-270000D01*
X778055Y-269790D01*
X778603Y-269370D01*
X778995Y-268635D01*
X779073Y-267795D01*
X778917Y-266955D01*
X778525Y-266430D01*
X777977Y-266010D01*
X777428Y-265905D01*
X776880Y-266010D01*
X776175Y-266430D01*
X776410Y-263700D01*
X778525D01*
G01X783650D02*
X783023Y-263910D01*
X782553Y-264435D01*
X782240Y-265065D01*
X782005Y-265905D01*
X781927Y-266850D01*
X782005Y-267795D01*
X782240Y-268635D01*
X782553Y-269265D01*
X783023Y-269790D01*
X783650Y-270000D01*
X784277Y-269790D01*
X784747Y-269265D01*
X785060Y-268635D01*
X785295Y-267795D01*
X785373Y-266850D01*
X785295Y-265905D01*
X785060Y-265065D01*
X784747Y-264435D01*
X784277Y-263910D01*
X783650Y-263700D01*
G01X790890Y-270000D02*
Y-263700D01*
X787992Y-268215D01*
X791908D01*
G01X796250Y-270000D02*
X796798Y-269895D01*
X797425Y-269580D01*
X797817Y-269055D01*
X797973Y-268320D01*
X797817Y-267585D01*
X797347Y-266955D01*
X796642Y-266640D01*
X795858D01*
X795388Y-266430D01*
X794997Y-265905D01*
X794840Y-265170D01*
X795075Y-264435D01*
X795623Y-263910D01*
X796250Y-263700D01*
X796877Y-263910D01*
X797425Y-264435D01*
X797660Y-265170D01*
X797503Y-265905D01*
X797112Y-266430D01*
X796642Y-266640D01*
X795858D01*
X795153Y-266955D01*
X794683Y-267585D01*
X794527Y-268320D01*
X794683Y-269055D01*
X795075Y-269580D01*
X795702Y-269895D01*
X796250Y-270000D01*
G01X738322Y-319959D02*
Y-311959D01*
X737122Y-313559D01*
G01Y-319959D02*
X739522D01*
G01X744422Y-316626D02*
X745122Y-315692D01*
X745722Y-315159D01*
X746522Y-314892D01*
X747222Y-315159D01*
X747722Y-315692D01*
X748122Y-316492D01*
X748222Y-317426D01*
X748122Y-318226D01*
X747722Y-319026D01*
X747122Y-319692D01*
X746422Y-319959D01*
X745622Y-319692D01*
X744922Y-318893D01*
X744522Y-317692D01*
X744422Y-316359D01*
X744622Y-314626D01*
X744922Y-313692D01*
X745422Y-312759D01*
X746122Y-312092D01*
X746822Y-311959D01*
X747522Y-312226D01*
X748022Y-312892D01*
G01X754322Y-320226D02*
X754122Y-320092D01*
Y-319826D01*
X754322Y-319692D01*
X754522Y-319826D01*
Y-320092D01*
X754322Y-320226D01*
G01X760422Y-316626D02*
X761122Y-315692D01*
X761722Y-315159D01*
X762522Y-314892D01*
X763222Y-315159D01*
X763722Y-315692D01*
X764122Y-316492D01*
X764222Y-317426D01*
X764122Y-318226D01*
X763722Y-319026D01*
X763122Y-319692D01*
X762422Y-319959D01*
X761622Y-319692D01*
X760922Y-318893D01*
X760522Y-317692D01*
X760422Y-316359D01*
X760622Y-314626D01*
X760922Y-313692D01*
X761422Y-312759D01*
X762122Y-312092D01*
X762822Y-311959D01*
X763522Y-312226D01*
X764022Y-312892D01*
G01X783322Y-319959D02*
Y-311959D01*
X782122Y-313559D01*
G01Y-319959D02*
X784522D01*
G01X791122D02*
X791322Y-318226D01*
X791622Y-316759D01*
X792022Y-315426D01*
X792522Y-313959D01*
X793322Y-311959D01*
X789322D01*
G01X799322Y-320226D02*
X799122Y-320092D01*
Y-319826D01*
X799322Y-319692D01*
X799522Y-319826D01*
Y-320092D01*
X799322Y-320226D01*
G01X805422Y-313292D02*
X806022Y-312492D01*
X806722Y-312092D01*
X807522Y-311959D01*
X808522Y-312226D01*
X809222Y-312892D01*
X809422Y-313692D01*
X809322Y-314493D01*
X808922Y-315159D01*
X806922Y-316492D01*
X806022Y-317426D01*
X805422Y-318759D01*
X805222Y-319959D01*
X809422D01*
G01X803122Y-294959D02*
Y-286959D01*
X805122D01*
X805922Y-287359D01*
X806522Y-287892D01*
X807022Y-288692D01*
X807422Y-289626D01*
X807522Y-290959D01*
X807422Y-292292D01*
X807022Y-293226D01*
X806522Y-294026D01*
X805922Y-294559D01*
X805122Y-294959D01*
X803122D01*
G54D16*
X18244Y180800D03*
X29844D03*
X18195Y190606D03*
X29795D03*
X18251Y200306D03*
X29851D03*
X16232Y916362D03*
X27832D03*
X16232Y905862D03*
X27832D03*
X16232Y926862D03*
X27832D03*
X69600Y358228D03*
X58000D03*
X69600Y348228D03*
X58000D03*
X69600Y368228D03*
X58000D03*
X71874Y1081751D03*
X60274D03*
X71874Y1071251D03*
X60274D03*
X71874Y1092251D03*
X60274D03*
X125900Y1077600D03*
Y1088100D03*
Y1098600D03*
X132600Y358028D03*
X144200D03*
X132600Y348028D03*
X144200D03*
X132600Y368028D03*
X144200D03*
X137500Y1077600D03*
Y1088100D03*
Y1098600D03*
X170200Y187500D03*
Y197500D03*
X170100Y207400D03*
X167700Y912000D03*
Y932772D03*
Y922500D03*
X181800Y187500D03*
Y197500D03*
X181700Y207400D03*
X179300Y912000D03*
Y932772D03*
Y922500D03*
G54D25*
X27502Y268287D03*
Y265728D03*
Y263169D03*
Y995059D03*
Y992500D03*
Y989941D03*
X35080Y268287D03*
Y263169D03*
X44272Y278169D03*
Y283287D03*
X51850Y278169D03*
Y280728D03*
Y283287D03*
X35080Y995059D03*
Y989941D03*
X44772Y1004941D03*
Y1010059D03*
X52350Y1004941D03*
Y1007500D03*
Y1010059D03*
X158771Y268287D03*
Y263169D03*
X151193Y268287D03*
Y265728D03*
Y263169D03*
X153569Y278169D03*
Y283287D03*
X161147Y278169D03*
Y280728D03*
Y283287D03*
X153569Y1004941D03*
Y1010059D03*
X161147Y1004941D03*
Y1007500D03*
Y1010059D03*
X158771Y998208D03*
Y993090D03*
X151193Y998208D03*
Y995649D03*
Y993090D03*
G54D34*
X21185Y295736D03*
Y321720D03*
X21685Y1022508D03*
Y1048492D03*
X58167Y239736D03*
Y265720D03*
X59367Y963908D03*
Y989892D03*
X130482Y295736D03*
Y321720D03*
Y1022508D03*
Y1048492D03*
X182958Y237136D03*
Y263120D03*
X183800Y962708D03*
Y988692D03*
G54D26*
X15000Y271043D03*
Y998543D03*
X66561Y276685D03*
X67061Y1003457D03*
X136482Y269771D03*
Y999692D03*
X175858Y276685D03*
Y1003457D03*
G54D17*
X18351Y208906D03*
X25351D03*
X16462Y935899D03*
X23462D03*
X69500Y339300D03*
X62500D03*
X71649Y1062686D03*
X64649D03*
X134000Y339000D03*
X141000D03*
X131000Y1069000D03*
X138000D03*
X172177Y941600D03*
X179400Y215900D03*
X172400D03*
X179177Y941600D03*
G54D35*
X21685Y342406D03*
Y369178D03*
Y1069178D03*
Y1095950D03*
X181858Y342406D03*
Y369178D03*
X183800Y1069214D03*
Y1095986D03*
G54D36*
X17100Y1233000D03*
X22900D03*
G54D27*
X12047Y263957D03*
X17953D03*
Y271043D03*
X12047D03*
Y991457D03*
X17953D03*
Y998543D03*
X12047D03*
X69514Y283771D03*
X63608D03*
Y276685D03*
X69514D03*
X70014Y1010543D03*
X64108D03*
Y1003457D03*
X70014D03*
X133529Y262685D03*
X139435D03*
Y269771D03*
X133529D03*
Y992606D03*
X139435D03*
Y999692D03*
X133529D03*
X178811Y283771D03*
X172905D03*
Y276685D03*
X178811D03*
Y1010543D03*
X172905D03*
Y1003457D03*
X178811D03*
G54D18*
X13584Y223012D03*
Y949784D03*
X46478Y304940D03*
X46978Y1031712D03*
X137275Y223012D03*
Y952933D03*
X155775Y304940D03*
Y1031712D03*
G54D28*
X25984Y253500D03*
Y980500D03*
X40484Y664500D03*
X40547Y660519D03*
Y656519D03*
X40484Y668500D03*
Y684500D03*
Y680500D03*
Y672500D03*
Y676500D03*
G54D37*
X40667Y241228D03*
Y234228D03*
X38685Y305228D03*
Y312228D03*
X40867Y962300D03*
Y969300D03*
X39055Y1030668D03*
Y1037668D03*
X147982Y305228D03*
Y312228D03*
Y1032000D03*
Y1039000D03*
X164358Y241228D03*
Y234228D03*
X166258Y965649D03*
Y972649D03*
G54D19*
X16142Y223012D03*
X17717D03*
X19292D03*
X20867D03*
X22442D03*
X24016D03*
X25591D03*
X27166D03*
X28741D03*
X30316D03*
Y241516D03*
X28741D03*
X27166D03*
X25591D03*
X24016D03*
X22442D03*
X20867D03*
X19292D03*
X17717D03*
X16142D03*
Y949784D03*
X17717D03*
X19292D03*
X20867D03*
X22442D03*
X24016D03*
X25591D03*
X27166D03*
X28741D03*
X30316D03*
Y968288D03*
X28741D03*
X27166D03*
X25591D03*
X24016D03*
X22442D03*
X20867D03*
X19292D03*
X17717D03*
X16142D03*
X49036Y304940D03*
X50611D03*
X52186D03*
X53761D03*
Y323444D03*
X52186D03*
X50611D03*
X49036D03*
X49536Y1031712D03*
X51111D03*
X52686D03*
X54261D03*
Y1050216D03*
X52686D03*
X51111D03*
X49536D03*
X55336Y304940D03*
X56910D03*
X58485D03*
X60060D03*
X61635D03*
X63210D03*
Y323444D03*
X61635D03*
X60060D03*
X58485D03*
X56910D03*
X55336D03*
X55836Y1031712D03*
X57410D03*
X58985D03*
X60560D03*
X62135D03*
X63710D03*
Y1050216D03*
X62135D03*
X60560D03*
X58985D03*
X57410D03*
X55836D03*
X139833Y223012D03*
X141408D03*
X142983D03*
X144558D03*
X146133D03*
Y241516D03*
X144558D03*
X142983D03*
X141408D03*
X139833D03*
Y952933D03*
X141408D03*
X142983D03*
X144558D03*
X146133D03*
Y971437D03*
X144558D03*
X142983D03*
X141408D03*
X139833D03*
X147707Y223012D03*
X149282D03*
X150857D03*
X152432D03*
X154007D03*
Y241516D03*
X152432D03*
X150857D03*
X149282D03*
X147707D03*
X158333Y304940D03*
X159908D03*
X161483D03*
X163058D03*
X164633D03*
X166207D03*
X167782D03*
X169357D03*
Y323444D03*
X167782D03*
X166207D03*
X164633D03*
X163058D03*
X161483D03*
X159908D03*
X158333D03*
X147707Y952933D03*
X149282D03*
X150857D03*
X152432D03*
X154007D03*
Y971437D03*
X152432D03*
X150857D03*
X149282D03*
X147707D03*
X158333Y1031712D03*
X159908D03*
X161483D03*
X163058D03*
X164633D03*
X166207D03*
X167782D03*
X169357D03*
Y1050216D03*
X167782D03*
X166207D03*
X164633D03*
X163058D03*
X161483D03*
X159908D03*
X158333D03*
X170932Y304940D03*
X172507D03*
Y323444D03*
X170932D03*
Y1031712D03*
X172507D03*
Y1050216D03*
X170932D03*
G54D29*
X23017Y253500D03*
Y980500D03*
X37517Y664500D03*
X37580Y660519D03*
Y656519D03*
X37517Y668500D03*
Y684500D03*
Y680500D03*
Y672500D03*
Y676500D03*
G54D38*
X49824Y309468D03*
X50324Y1036240D03*
X159121Y309468D03*
Y1036240D03*
G54D39*
X72561Y292803D03*
Y289653D03*
X77061D03*
Y292803D03*
M02*
